# BASEBOARD_FAB2 (Tioga Pass) — schematic netlist excerpt (pin names and nets, part order shuffled) for the footprints in the layout excerpt that follows; sources: Cadence DE-HDL packaged netlist, KiCad conversion of Wiwynn_Tioga_Pass_MB.brd

C7P7  CAP  100UF 4V 20% X5R  pkg 0805  page 76 : A = PVCCMCP_CPU1 ; B = GND
C9T6  CAP  10UF 16V 10% X6S  pkg 0805  page 224 : A = VR_FET_SW_P12V_STBY_PVDDQ_GHJ ; B = GND
C25W51  CAP  1.0UF 16V 10% X6S  pkg 0402  page 149 : A = P1V2_AUX_BMC ; B = GND
C7W10  SC22U16V5MX-4-GP  20%  pkg SMD-BCG5  page 220 : \1\ = VR_FET_SW_P12V_STBY_PVDDQ_DEF ; \2\ = GND

(kicad_pcb
	(version 20260206)
	(generator "pcbnew")
	(generator_version "10.0")
	(general
		(thickness 1.6)
		(legacy_teardrops no)
	)
	(paper "A4")
	(title_block
		(title "Wiwynn_Tioga_Pass_MB.brd")
		(comment 1 "Tioga Pass / footprints 4255-4258 of 4770")
	)
	(layers
		(0 "F.Cu" signal "TOP")
		(4 "In1.Cu" signal "L2GND")
		(6 "In2.Cu" signal "L3")
		(8 "In3.Cu" signal "L4GND")
		(10 "In4.Cu" signal "L5")
		(12 "In5.Cu" signal "L6GND")
		(14 "In6.Cu" signal "L7VCC")
		(16 "In7.Cu" signal "L8VCC")
		(18 "In8.Cu" signal "L9GND")
		(20 "In9.Cu" signal "L10")
		(22 "In10.Cu" signal "L11GND")
		(24 "In11.Cu" signal "L12")
		(26 "In12.Cu" signal "L13GND")
		(2 "B.Cu" signal "BOTTOM")
		(9 "F.Adhes" user "F.Adhesive")
		(11 "B.Adhes" user "B.Adhesive")
		(13 "F.Paste" user "Package Geometry/Pastemask Top")
		(15 "B.Paste" user "Package Geometry/Pastemask Bottom")
		(5 "F.SilkS" user "Ref Des/Silkscreen Top")
		(7 "B.SilkS" user "Ref Des/Silkscreen Bottom")
		(1 "F.Mask" user "Board Geometry/Soldermask Top")
		(3 "B.Mask" user "Board Geometry/Soldermask Bottom")
		(17 "Dwgs.User" user "User.Drawings")
		(19 "Cmts.User" user "User.Comments")
		(21 "Eco1.User" user "User.Eco1")
		(23 "Eco2.User" user "User.Eco2")
		(25 "Edge.Cuts" user "Board Geometry/Outline")
		(27 "Margin" user)
		(31 "F.CrtYd" user "Package Geometry/Place Bound Top")
		(29 "B.CrtYd" user "Package Geometry/Place Bound Bottom")
		(35 "F.Fab" user "Ref Des/Assembly Top")
		(33 "B.Fab" user "Ref Des/Assembly Bottom")
	)
	(footprint ""
		(layer "B.Cu")
		(at 353.64801 -143.629888 90)
		(property "Reference" "C7W10"
			(at 0 0 90)
			(layer "B.SilkS")
			(hide yes)
			(effects
				(font
					(size 1.27 1.27)
				)
				(justify mirror)
			)
		)
		(property "Value" "*"
			(at 0.0762 -6.2357 90)
			(unlocked yes)
			(layer "B.Fab")
			(hide yes)
			(effects
				(font
					(size 1.27 1.016)
					(thickness 0.1524)
				)
				(justify mirror)
			)
		)
		(property "Device Type" "SC22U16V5MX-4-GP_SMD-BCG5-SC22A"
			(at 0.0762 -8.2677 90)
			(unlocked yes)
			(layer "B.Fab")
			(hide yes)
			(effects
				(font
					(size 1.27 1.016)
					(thickness 0.1524)
				)
				(justify mirror)
			)
		)
		(duplicate_pad_numbers_are_jumpers no)
		(fp_line
			(start -0.635 0)
			(end 0.635 0)
			(stroke
				(width 0.508)
				(type default)
			)
			(layer "B.SilkS")
		)
		(fp_rect
			(start 0.9652 1.778)
			(end -0.9652 -1.778)
			(stroke
				(width 0)
				(type default)
			)
			(fill no)
			(layer "B.CrtYd")
		)
		(fp_poly
			(pts
				(xy 0.9652 -1.778) (xy -0.9652 -1.778) (xy -0.9652 1.778) (xy 0.9652 1.778)
			)
			(stroke
				(width 0)
				(type default)
			)
			(fill no)
			(layer "B.Fab")
		)
		(pad "1" smd rect
			(at 0 -0.9652 270)
			(size 1.397 1.143)
			(layers "B.Cu" "B.Mask" "B.Paste")
			(net "VR_FET_SW_P12V_STBY_PVDDQ_DEF")
		)
		(pad "2" smd rect
			(at 0 0.9652 270)
			(size 1.397 1.143)
			(layers "B.Cu" "B.Mask" "B.Paste")
			(net "GND")
		)
	)
	(footprint ""
		(layer "B.Cu")
		(at 108.559854 -79.60614 180)
		(property "Reference" "C7P7"
			(at 0 0 0)
			(layer "B.SilkS")
			(hide yes)
			(effects
				(font
					(size 1.27 1.27)
				)
				(justify mirror)
			)
		)
		(property "Value" ""
			(at 0 0 0)
			(layer "B.Fab")
			(effects
				(font
					(size 1.27 1.27)
				)
				(justify mirror)
			)
		)
		(duplicate_pad_numbers_are_jumpers no)
		(fp_poly
			(pts
				(xy 0.7239 -0.2159) (xy -0.7239 -0.2159) (xy -0.7239 1.9939) (xy 0.7239 1.9939)
			)
			(stroke
				(width 0)
				(type default)
			)
			(fill no)
			(layer "B.CrtYd")
		)
		(fp_line
			(start 0.7239 1.9939)
			(end -0.7239 1.9939)
			(stroke
				(width 0.1)
				(type default)
			)
			(layer "B.Fab")
		)
		(fp_line
			(start 0.7239 -0.2159)
			(end 0.7239 1.9939)
			(stroke
				(width 0.1)
				(type default)
			)
			(layer "B.Fab")
		)
		(fp_line
			(start -0.7239 1.9939)
			(end -0.7239 -0.2159)
			(stroke
				(width 0.1)
				(type default)
			)
			(layer "B.Fab")
		)
		(fp_line
			(start -0.7239 -0.2159)
			(end 0.7239 -0.2159)
			(stroke
				(width 0.1)
				(type default)
			)
			(layer "B.Fab")
		)
		(pad "1" smd rect
			(at 0 0)
			(size 1.27 1.016)
			(layers "B.Cu" "B.Mask" "B.Paste")
			(net "PVCCMCP_CPU1")
		)
		(pad "2" smd rect
			(at 0 1.778)
			(size 1.27 1.016)
			(layers "B.Cu" "B.Mask" "B.Paste")
			(net "GND")
		)
		(zone
			(layer "B.Cu")
			(hatch none 0.5)
			(connect_pads
				(clearance 0)
			)
			(min_thickness 0.25)
			(keepout
				(tracks not_allowed)
				(vias allowed)
				(pads allowed)
				(copperpour not_allowed)
				(footprints allowed)
			)
			(placement
				(enabled no)
				(sheetname "")
			)
			(fill
				(thermal_gap 0.5)
				(thermal_bridge_width 0.5)
				(island_removal_mode 0)
			)
			(polygon
				(pts
					(xy 107.924854 -80.11414) (xy 109.194854 -80.11414) (xy 109.194854 -80.87614) (xy 107.924854 -80.87614)
				)
			)
		)
	)
	(footprint ""
		(layer "B.Cu")
		(at 3.893312 -18.586196 90)
		(property "Reference" "C9T6"
			(at 0 0 90)
			(layer "B.SilkS")
			(hide yes)
			(effects
				(font
					(size 1.27 1.27)
				)
				(justify mirror)
			)
		)
		(property "Value" ""
			(at 0 0 90)
			(layer "B.Fab")
			(effects
				(font
					(size 1.27 1.27)
				)
				(justify mirror)
			)
		)
		(duplicate_pad_numbers_are_jumpers no)
		(fp_rect
			(start -0.7239 -0.2159)
			(end 0.7239 1.9939)
			(stroke
				(width 0)
				(type default)
			)
			(fill no)
			(layer "B.CrtYd")
		)
		(fp_line
			(start 0.7239 -0.2159)
			(end 0.7239 1.9939)
			(stroke
				(width 0.1)
				(type default)
			)
			(layer "B.Fab")
		)
		(fp_line
			(start -0.7239 -0.2159)
			(end 0.7239 -0.2159)
			(stroke
				(width 0.1)
				(type default)
			)
			(layer "B.Fab")
		)
		(fp_line
			(start 0.7239 1.9939)
			(end -0.7239 1.9939)
			(stroke
				(width 0.1)
				(type default)
			)
			(layer "B.Fab")
		)
		(fp_line
			(start -0.7239 1.9939)
			(end -0.7239 -0.2159)
			(stroke
				(width 0.1)
				(type default)
			)
			(layer "B.Fab")
		)
		(pad "1" smd rect
			(at 0 0 270)
			(size 1.27 1.016)
			(layers "B.Cu" "B.Mask" "B.Paste")
			(net "VR_FET_SW_P12V_STBY_PVDDQ_GHJ")
		)
		(pad "2" smd rect
			(at 0 1.778 270)
			(size 1.27 1.016)
			(layers "B.Cu" "B.Mask" "B.Paste")
			(net "GND")
		)
		(zone
			(layer "B.Cu")
			(hatch none 0.5)
			(connect_pads
				(clearance 0)
			)
			(min_thickness 0.25)
			(keepout
				(tracks not_allowed)
				(vias allowed)
				(pads allowed)
				(copperpour not_allowed)
				(footprints allowed)
			)
			(placement
				(enabled no)
				(sheetname "")
			)
			(fill
				(thermal_gap 0.5)
				(thermal_bridge_width 0.5)
				(island_removal_mode 0)
			)
			(polygon
				(pts
					(xy 4.401312 -17.951196) (xy 5.163312 -17.951196) (xy 5.163312 -19.221196) (xy 4.401312 -19.221196)
				)
			)
		)
	)
	(footprint ""
		(layer "B.Cu")
		(at 418.870638 -37.5285 -90)
		(property "Reference" "C25W51"
			(at 0.8382 -0.67818 270)
			(unlocked yes)
			(layer "B.SilkS")
			(effects
				(font
					(size 0.4064 0.254)
					(thickness 0.1524)
				)
				(justify left mirror)
			)
		)
		(property "Value" ""
			(at 0 0 90)
			(layer "B.Fab")
			(effects
				(font
					(size 1.27 1.27)
				)
				(justify mirror)
			)
		)
		(duplicate_pad_numbers_are_jumpers no)
		(fp_poly
			(pts
				(xy -0.3048 -0.1016) (xy -0.3048 0.9906) (xy 0.3048 0.9906) (xy 0.3048 -0.1016)
			)
			(stroke
				(width 0)
				(type default)
			)
			(fill no)
			(layer "B.CrtYd")
		)
		(fp_line
			(start -0.3048 0.9906)
			(end -0.3048 -0.1016)
			(stroke
				(width 0.1)
				(type default)
			)
			(layer "B.Fab")
		)
		(fp_line
			(start 0.3048 0.9906)
			(end -0.3048 0.9906)
			(stroke
				(width 0.1)
				(type default)
			)
			(layer "B.Fab")
		)
		(fp_line
			(start -0.3048 -0.1016)
			(end 0.3048 -0.1016)
			(stroke
				(width 0.1)
				(type default)
			)
			(layer "B.Fab")
		)
		(fp_line
			(start 0.3048 -0.1016)
			(end 0.3048 0.9906)
			(stroke
				(width 0.1)
				(type default)
			)
			(layer "B.Fab")
		)
		(pad "1" smd rect
			(at 0 0 90)
			(size 0.508 0.508)
			(layers "B.Cu" "B.Mask" "B.Paste")
			(net "P1V2_AUX_BMC")
		)
		(pad "2" smd rect
			(at 0 0.889 90)
			(size 0.508 0.508)
			(layers "B.Cu" "B.Mask" "B.Paste")
			(net "GND")
		)
		(zone
			(layer "B.Cu")
			(hatch none 0.5)
			(connect_pads
				(clearance 0)
			)
			(min_thickness 0.25)
			(keepout
				(tracks not_allowed)
				(vias allowed)
				(pads allowed)
				(copperpour not_allowed)
				(footprints allowed)
			)
			(placement
				(enabled no)
				(sheetname "")
			)
			(fill
				(thermal_gap 0.5)
				(thermal_bridge_width 0.5)
				(island_removal_mode 0)
			)
			(polygon
				(pts
					(xy 418.235638 -37.2745) (xy 418.235638 -37.7825) (xy 418.616638 -37.7825) (xy 418.616638 -37.2745)
				)
			)
		)
		(zone
			(layer "B.Cu")
			(hatch none 0.5)
			(connect_pads
				(clearance 0)
			)
			(min_thickness 0.25)
			(keepout
				(tracks allowed)
				(vias not_allowed)
				(pads allowed)
				(copperpour not_allowed)
				(footprints allowed)
			)
			(placement
				(enabled no)
				(sheetname "")
			)
			(fill
				(thermal_gap 0.5)
				(thermal_bridge_width 0.5)
				(island_removal_mode 0)
			)
			(polygon
				(pts
					(xy 418.616638 -37.2745) (xy 418.616638 -37.7825) (xy 418.235638 -37.7825) (xy 418.235638 -37.2745)
				)
			)
		)
	)
)
